# S9S_MB_2U (Grand Teton) — schematic netlist excerpt (pin names and nets, part order shuffled) for the footprints in the layout excerpt that follows; sources: Cadence DE-HDL packaged netlist, KiCad conversion of 03242023_DA0F0TMBIJ0_F0T_Motherboard_J_brd_V01_OCP.brd

R2502  Q_RES  33.2 1% CHIP  pkg 0402LF  page 115 : A = PWRGD_FAIL_CPU1_AB_R1 ; B = PWRGD_FAIL_CPU1_AB_R
PR283  Q_RES  1 1% CHIP  pkg 0402LF  page 292 : A = PVCCINFAON_CPU1_VCC ; B = P3V3_AUX
C1246  Q_CAP  47UF 4V 20% X6S  pkg C0805  page 189 : A = P1V05_PCH_AUX ; B = GND

(kicad_pcb
	(version 20260206)
	(generator "pcbnew")
	(generator_version "10.0")
	(general
		(thickness 1.6)
		(legacy_teardrops no)
	)
	(paper "A4")
	(title_block
		(title "03242023_DA0F0TMBIJ0_F0T_Motherboard_J_brd_V01_OCP.brd")
		(comment 1 "Grand Teton / footprints 5525-5527 of 6105")
	)
	(layers
		(0 "F.Cu" signal "TOP")
		(4 "In1.Cu" signal "GND")
		(6 "In2.Cu" signal "IN1")
		(8 "In3.Cu" signal "GND1")
		(10 "In4.Cu" signal "IN2")
		(12 "In5.Cu" signal "GND2")
		(14 "In6.Cu" signal "IN3")
		(16 "In7.Cu" signal "GND3")
		(18 "In8.Cu" signal "VCC")
		(20 "In9.Cu" signal "VCC1")
		(22 "In10.Cu" signal "GND4")
		(24 "In11.Cu" signal "IN4")
		(26 "In12.Cu" signal "GND5")
		(28 "In13.Cu" signal "IN5")
		(30 "In14.Cu" signal "GND6")
		(32 "In15.Cu" signal "IN6")
		(34 "In16.Cu" signal "GND7")
		(2 "B.Cu" signal "BOTTOM")
		(9 "F.Adhes" user "F.Adhesive")
		(11 "B.Adhes" user "B.Adhesive")
		(13 "F.Paste" user "Package Geometry/Pastemask Top")
		(15 "B.Paste" user "Package Geometry/Pastemask Bottom")
		(5 "F.SilkS" user "Ref Des/Silkscreen Top")
		(7 "B.SilkS" user "Ref Des/Silkscreen Bottom")
		(1 "F.Mask" user "Board Geometry/Soldermask Top")
		(3 "B.Mask" user "Board Geometry/Soldermask Bottom")
		(17 "Dwgs.User" user "User.Drawings")
		(19 "Cmts.User" user "User.Comments")
		(21 "Eco1.User" user "User.Eco1")
		(23 "Eco2.User" user "User.Eco2")
		(25 "Edge.Cuts" user "Board Geometry/Outline")
		(27 "Margin" user)
		(31 "F.CrtYd" user "Package Geometry/Place Bound Top")
		(29 "B.CrtYd" user "Package Geometry/Place Bound Bottom")
		(35 "F.Fab" user "Ref Des/Assembly Top")
		(33 "B.Fab" user "Ref Des/Assembly Bottom")
	)
	(footprint ""
		(layer "B.Cu")
		(at 69.772022 -318.385444 90)
		(property "Reference" "R2502"
			(at 0 0 90)
			(layer "B.SilkS")
			(hide yes)
			(effects
				(font
					(size 1.27 1.27)
				)
				(justify mirror)
			)
		)
		(property "Value" ""
			(at 0 0 90)
			(layer "B.Fab")
			(effects
				(font
					(size 1.27 1.27)
				)
				(justify mirror)
			)
		)
		(duplicate_pad_numbers_are_jumpers no)
		(fp_line
			(start 0.7874 -0.4064)
			(end -0.7874 -0.4064)
			(stroke
				(width 0.1524)
				(type default)
			)
			(layer "B.SilkS")
		)
		(fp_line
			(start -0.7874 -0.4064)
			(end -0.7874 0.4064)
			(stroke
				(width 0.1524)
				(type default)
			)
			(layer "B.SilkS")
		)
		(fp_line
			(start 0.7874 0.4064)
			(end 0.7874 -0.4064)
			(stroke
				(width 0.1524)
				(type default)
			)
			(layer "B.SilkS")
		)
		(fp_line
			(start -0.7874 0.4064)
			(end 0.7874 0.4064)
			(stroke
				(width 0.1524)
				(type default)
			)
			(layer "B.SilkS")
		)
		(fp_line
			(start 0.67945 -0.305054)
			(end 0.12065 -0.305054)
			(stroke
				(width 0.1)
				(type default)
			)
			(layer "B.Fab")
		)
		(fp_line
			(start 0.12065 -0.305054)
			(end 0.12065 -0.2794)
			(stroke
				(width 0.1)
				(type default)
			)
			(layer "B.Fab")
		)
		(fp_line
			(start -0.12065 -0.3048)
			(end -0.67945 -0.3048)
			(stroke
				(width 0.1)
				(type default)
			)
			(layer "B.Fab")
		)
		(fp_line
			(start -0.67945 -0.3048)
			(end -0.67945 0.3048)
			(stroke
				(width 0.1)
				(type default)
			)
			(layer "B.Fab")
		)
		(fp_line
			(start 0.12065 -0.2794)
			(end -0.12065 -0.2794)
			(stroke
				(width 0.1)
				(type default)
			)
			(layer "B.Fab")
		)
		(fp_line
			(start -0.12065 -0.2794)
			(end -0.12065 -0.3048)
			(stroke
				(width 0.1)
				(type default)
			)
			(layer "B.Fab")
		)
		(fp_line
			(start 0.12065 0.2794)
			(end 0.12065 0.3048)
			(stroke
				(width 0.1)
				(type default)
			)
			(layer "B.Fab")
		)
		(fp_line
			(start -0.120396 0.2794)
			(end 0.12065 0.2794)
			(stroke
				(width 0.1)
				(type default)
			)
			(layer "B.Fab")
		)
		(fp_line
			(start 0.67945 0.3048)
			(end 0.67945 -0.305054)
			(stroke
				(width 0.1)
				(type default)
			)
			(layer "B.Fab")
		)
		(fp_line
			(start 0.12065 0.3048)
			(end 0.67945 0.3048)
			(stroke
				(width 0.1)
				(type default)
			)
			(layer "B.Fab")
		)
		(fp_line
			(start -0.120396 0.3048)
			(end -0.120396 0.2794)
			(stroke
				(width 0.1)
				(type default)
			)
			(layer "B.Fab")
		)
		(fp_line
			(start -0.67945 0.3048)
			(end -0.120396 0.3048)
			(stroke
				(width 0.1)
				(type default)
			)
			(layer "B.Fab")
		)
		(pad "1" smd circle
			(at 0.40005 0 270)
			(size 0 0)
			(layers "B.Cu" "B.Mask" "B.Paste")
			(net "PWRGD_FAIL_CPU1_AB_R1")
		)
		(pad "2" smd circle
			(at -0.40005 0 270)
			(size 0 0)
			(layers "B.Cu" "B.Mask" "B.Paste")
			(net "PWRGD_FAIL_CPU1_AB_R")
		)
	)
	(footprint ""
		(layer "B.Cu")
		(at 27.0383 -125.342396)
		(property "Reference" "PR283"
			(at 0 0 0)
			(layer "B.SilkS")
			(hide yes)
			(effects
				(font
					(size 1.27 1.27)
				)
				(justify mirror)
			)
		)
		(property "Value" ""
			(at 0 0 0)
			(layer "B.Fab")
			(effects
				(font
					(size 1.27 1.27)
				)
				(justify mirror)
			)
		)
		(duplicate_pad_numbers_are_jumpers no)
		(fp_line
			(start -0.7874 -0.4064)
			(end -0.7874 0.4064)
			(stroke
				(width 0.1524)
				(type default)
			)
			(layer "B.SilkS")
		)
		(fp_line
			(start -0.7874 0.4064)
			(end 0.7874 0.4064)
			(stroke
				(width 0.1524)
				(type default)
			)
			(layer "B.SilkS")
		)
		(fp_line
			(start 0.7874 -0.4064)
			(end -0.7874 -0.4064)
			(stroke
				(width 0.1524)
				(type default)
			)
			(layer "B.SilkS")
		)
		(fp_line
			(start 0.7874 0.4064)
			(end 0.7874 -0.4064)
			(stroke
				(width 0.1524)
				(type default)
			)
			(layer "B.SilkS")
		)
		(fp_line
			(start -0.67945 -0.3048)
			(end -0.67945 0.3048)
			(stroke
				(width 0.1)
				(type default)
			)
			(layer "B.Fab")
		)
		(fp_line
			(start -0.67945 0.3048)
			(end -0.120396 0.3048)
			(stroke
				(width 0.1)
				(type default)
			)
			(layer "B.Fab")
		)
		(fp_line
			(start -0.12065 -0.3048)
			(end -0.67945 -0.3048)
			(stroke
				(width 0.1)
				(type default)
			)
			(layer "B.Fab")
		)
		(fp_line
			(start -0.12065 -0.2794)
			(end -0.12065 -0.3048)
			(stroke
				(width 0.1)
				(type default)
			)
			(layer "B.Fab")
		)
		(fp_line
			(start -0.120396 0.2794)
			(end 0.12065 0.2794)
			(stroke
				(width 0.1)
				(type default)
			)
			(layer "B.Fab")
		)
		(fp_line
			(start -0.120396 0.3048)
			(end -0.120396 0.2794)
			(stroke
				(width 0.1)
				(type default)
			)
			(layer "B.Fab")
		)
		(fp_line
			(start 0.12065 -0.305054)
			(end 0.12065 -0.2794)
			(stroke
				(width 0.1)
				(type default)
			)
			(layer "B.Fab")
		)
		(fp_line
			(start 0.12065 -0.2794)
			(end -0.12065 -0.2794)
			(stroke
				(width 0.1)
				(type default)
			)
			(layer "B.Fab")
		)
		(fp_line
			(start 0.12065 0.2794)
			(end 0.12065 0.3048)
			(stroke
				(width 0.1)
				(type default)
			)
			(layer "B.Fab")
		)
		(fp_line
			(start 0.12065 0.3048)
			(end 0.67945 0.3048)
			(stroke
				(width 0.1)
				(type default)
			)
			(layer "B.Fab")
		)
		(fp_line
			(start 0.67945 -0.305054)
			(end 0.12065 -0.305054)
			(stroke
				(width 0.1)
				(type default)
			)
			(layer "B.Fab")
		)
		(fp_line
			(start 0.67945 0.3048)
			(end 0.67945 -0.305054)
			(stroke
				(width 0.1)
				(type default)
			)
			(layer "B.Fab")
		)
		(pad "1" smd circle
			(at 0.40005 0 180)
			(size 0 0)
			(layers "B.Cu" "B.Mask" "B.Paste")
			(net "PVCCINFAON_CPU1_VCC")
		)
		(pad "2" smd circle
			(at -0.40005 0 180)
			(size 0 0)
			(layers "B.Cu" "B.Mask" "B.Paste")
			(net "P3V3_AUX")
		)
	)
	(footprint ""
		(layer "B.Cu")
		(at 297.419776 -46.40199)
		(property "Reference" "C1246"
			(at 0 0 0)
			(layer "B.SilkS")
			(hide yes)
			(effects
				(font
					(size 1.27 1.27)
				)
				(justify mirror)
			)
		)
		(property "Value" ""
			(at 0 0 0)
			(layer "B.Fab")
			(effects
				(font
					(size 1.27 1.27)
				)
				(justify mirror)
			)
		)
		(duplicate_pad_numbers_are_jumpers no)
		(fp_line
			(start -1.524 -0.762)
			(end -1.524 0.762)
			(stroke
				(width 0.1524)
				(type default)
			)
			(layer "B.SilkS")
		)
		(fp_line
			(start -1.524 0.762)
			(end 1.524 0.762)
			(stroke
				(width 0.1524)
				(type default)
			)
			(layer "B.SilkS")
		)
		(fp_line
			(start 1.524 -0.762)
			(end -1.524 -0.762)
			(stroke
				(width 0.1524)
				(type default)
			)
			(layer "B.SilkS")
		)
		(fp_line
			(start 1.524 0.762)
			(end 1.524 -0.762)
			(stroke
				(width 0.1524)
				(type default)
			)
			(layer "B.SilkS")
		)
		(fp_line
			(start -1.1049 -0.724916)
			(end 1.1049 -0.724916)
			(stroke
				(width 0.1)
				(type default)
			)
			(layer "B.Fab")
		)
		(fp_line
			(start -1.1049 0.724916)
			(end -1.1049 -0.724916)
			(stroke
				(width 0.1)
				(type default)
			)
			(layer "B.Fab")
		)
		(fp_line
			(start 1.1049 -0.724916)
			(end 1.1049 0.724916)
			(stroke
				(width 0.1)
				(type default)
			)
			(layer "B.Fab")
		)
		(fp_line
			(start 1.1049 0.724916)
			(end -1.1049 0.724916)
			(stroke
				(width 0.1)
				(type default)
			)
			(layer "B.Fab")
		)
		(pad "1" smd rect
			(at 0.889 0)
			(size 1.016 1.27)
			(layers "B.Cu" "B.Mask" "B.Paste")
			(net "P1V05_PCH_AUX")
		)
		(pad "2" smd rect
			(at -0.889 0)
			(size 1.016 1.27)
			(layers "B.Cu" "B.Mask" "B.Paste")
			(net "GND")
		)
	)
)
